# T6G (Grand Teton) — schematic netlist excerpt (pin names and nets, part order shuffled) for the footprints in the layout excerpt that follows; sources: Cadence DE-HDL packaged netlist, KiCad conversion of 04192023_DAF0TMB3IC0_F0TG_MB_C_brd_V02_OCP.brd

C957  Q_CAP_DIFFBUS  DIFF BUS_0.22UF 6.3V 20% X6S  pkg C0201  page 63 : \1\ = P5E_CPU0_P1_TX_C_DP<4> ; \2\ = P5E_CPU0_P1_TX_DP<4>
R699  Q_RES  1K 1% EMPTY  pkg 0201LF  page 321 : A = P1V8_CPU1_RT_1D ; B = RT_CPU1_P0_VQPS

U8008  AP331AWG7  AP331AWG-7 IC  pkg SOT25  page 268
  \in-\  = UV_ADR_P2V5_COMP
  GND  = GND
  \in+\  = P12V_AUX_UV_ADR_TRIGGER
  OUTPUT  = FM_UV_ADR_TRIGGER_N_R2
  VCC  = P12V_AUX

(kicad_pcb
	(version 20260206)
	(generator "pcbnew")
	(generator_version "10.0")
	(general
		(thickness 1.6)
		(legacy_teardrops no)
	)
	(paper "A4")
	(title_block
		(title "04192023_DAF0TMB3IC0_F0TG_MB_C_brd_V02_OCP.brd")
		(comment 1 "Grand Teton / footprints 35-37 of 8354")
	)
	(layers
		(0 "F.Cu" signal "TOP")
		(4 "In1.Cu" signal "GND")
		(6 "In2.Cu" signal "IN1")
		(8 "In3.Cu" signal "GND1")
		(10 "In4.Cu" signal "IN2")
		(12 "In5.Cu" signal "GND2")
		(14 "In6.Cu" signal "IN3")
		(16 "In7.Cu" signal "GND3")
		(18 "In8.Cu" signal "VCC")
		(20 "In9.Cu" signal "VCC1")
		(22 "In10.Cu" signal "GND4")
		(24 "In11.Cu" signal "IN4")
		(26 "In12.Cu" signal "GND5")
		(28 "In13.Cu" signal "IN5")
		(30 "In14.Cu" signal "GND6")
		(32 "In15.Cu" signal "IN6")
		(34 "In16.Cu" signal "GND7")
		(2 "B.Cu" signal "BOTTOM")
		(9 "F.Adhes" user "F.Adhesive")
		(11 "B.Adhes" user "B.Adhesive")
		(13 "F.Paste" user "Package Geometry/Pastemask Top")
		(15 "B.Paste" user "Package Geometry/Pastemask Bottom")
		(5 "F.SilkS" user "Ref Des/Silkscreen Top")
		(7 "B.SilkS" user "Ref Des/Silkscreen Bottom")
		(1 "F.Mask" user "Board Geometry/Soldermask Top")
		(3 "B.Mask" user "Board Geometry/Soldermask Bottom")
		(17 "Dwgs.User" user "User.Drawings")
		(19 "Cmts.User" user "User.Comments")
		(21 "Eco1.User" user "User.Eco1")
		(23 "Eco2.User" user "User.Eco2")
		(25 "Edge.Cuts" user "Board Geometry/Outline")
		(27 "Margin" user)
		(31 "F.CrtYd" user "Package Geometry/Place Bound Top")
		(29 "B.CrtYd" user "Package Geometry/Place Bound Bottom")
		(35 "F.Fab" user "Ref Des/Assembly Top")
		(33 "B.Fab" user "Ref Des/Assembly Bottom")
	)
	(footprint ""
		(layer "F.Cu")
		(at 336.622644 -383.88163 -90)
		(property "Reference" "C957"
			(at 0 0 270)
			(layer "F.SilkS")
			(hide yes)
			(effects
				(font
					(size 1.27 1.27)
				)
			)
		)
		(property "Value" ""
			(at 0 0 270)
			(layer "F.Fab")
			(effects
				(font
					(size 1.27 1.27)
				)
			)
		)
		(duplicate_pad_numbers_are_jumpers no)
		(fp_line
			(start -0.299974 0.150114)
			(end -0.299974 -0.150114)
			(stroke
				(width 0.1)
				(type default)
			)
			(layer "F.Fab")
		)
		(fp_line
			(start 0.299974 0.150114)
			(end -0.299974 0.150114)
			(stroke
				(width 0.1)
				(type default)
			)
			(layer "F.Fab")
		)
		(fp_line
			(start -0.299974 -0.150114)
			(end 0.299974 -0.150114)
			(stroke
				(width 0.1)
				(type default)
			)
			(layer "F.Fab")
		)
		(fp_line
			(start 0.299974 -0.150114)
			(end 0.299974 0.150114)
			(stroke
				(width 0.1)
				(type default)
			)
			(layer "F.Fab")
		)
		(pad "1" smd rect
			(at -0.2667 0 270)
			(size 0.3048 0.381)
			(layers "F.Cu" "F.Mask" "F.Paste")
			(net "P5E_CPU0_P1_TX_C_DP<4>")
		)
		(pad "2" smd rect
			(at 0.2667 0 270)
			(size 0.3048 0.381)
			(layers "F.Cu" "F.Mask" "F.Paste")
			(net "P5E_CPU0_P1_TX_DP<4>")
		)
	)
	(footprint ""
		(layer "F.Cu")
		(at 66.42862 -394.78458 90)
		(property "Reference" "R699"
			(at 0 0 90)
			(layer "F.SilkS")
			(hide yes)
			(effects
				(font
					(size 1.27 1.27)
				)
			)
		)
		(property "Value" ""
			(at 0 0 90)
			(layer "F.Fab")
			(effects
				(font
					(size 1.27 1.27)
				)
			)
		)
		(duplicate_pad_numbers_are_jumpers no)
		(fp_line
			(start 0.32512 -0.175006)
			(end 0.32512 0.175006)
			(stroke
				(width 0.1)
				(type default)
			)
			(layer "F.Fab")
		)
		(fp_line
			(start -0.32512 -0.175006)
			(end 0.32512 -0.175006)
			(stroke
				(width 0.1)
				(type default)
			)
			(layer "F.Fab")
		)
		(fp_line
			(start 0.32512 0.175006)
			(end -0.32512 0.175006)
			(stroke
				(width 0.1)
				(type default)
			)
			(layer "F.Fab")
		)
		(fp_line
			(start -0.32512 0.175006)
			(end -0.32512 -0.175006)
			(stroke
				(width 0.1)
				(type default)
			)
			(layer "F.Fab")
		)
		(pad "1" smd rect
			(at -0.2667 0 90)
			(size 0.3048 0.381)
			(layers "F.Cu" "F.Mask" "F.Paste")
			(net "P1V8_CPU1_RT_1D")
		)
		(pad "2" smd rect
			(at 0.2667 0 270)
			(size 0.3048 0.381)
			(layers "F.Cu" "F.Mask" "F.Paste")
			(net "RT_CPU1_P0_VQPS")
		)
	)
	(footprint ""
		(layer "F.Cu")
		(at 133.223 -112.268)
		(property "Reference" "U8008"
			(at -1.405382 -3.298444 0)
			(unlocked yes)
			(layer "F.SilkS")
			(effects
				(font
					(size 0.7874 0.5842)
					(thickness 0.1524)
				)
			)
		)
		(property "Value" ""
			(at 0 0 0)
			(layer "F.Fab")
			(effects
				(font
					(size 1.27 1.27)
				)
			)
		)
		(duplicate_pad_numbers_are_jumpers no)
		(fp_line
			(start -2.032 -1.549908)
			(end -0.508 -1.549908)
			(stroke
				(width 0.1524)
				(type default)
			)
			(layer "F.SilkS")
		)
		(fp_line
			(start -2.032 1.549908)
			(end -2.032 -1.549908)
			(stroke
				(width 0.1524)
				(type default)
			)
			(layer "F.SilkS")
		)
		(fp_line
			(start -0.508 -1.549908)
			(end 0 -0.762)
			(stroke
				(width 0.1524)
				(type default)
			)
			(layer "F.SilkS")
		)
		(fp_line
			(start 0 -0.762)
			(end 0.508 -1.549908)
			(stroke
				(width 0.1524)
				(type default)
			)
			(layer "F.SilkS")
		)
		(fp_line
			(start 0.508 -1.549908)
			(end 2.032 -1.549908)
			(stroke
				(width 0.1524)
				(type default)
			)
			(layer "F.SilkS")
		)
		(fp_line
			(start 2.032 -1.549908)
			(end 2.032 1.549908)
			(stroke
				(width 0.1524)
				(type default)
			)
			(layer "F.SilkS")
		)
		(fp_line
			(start 2.032 1.549908)
			(end -2.032 1.549908)
			(stroke
				(width 0.1524)
				(type default)
			)
			(layer "F.SilkS")
		)
		(fp_poly
			(pts
				(xy -2.78003 -2.518918) (xy -3.441192 -1.74752) (xy -2.339086 -1.47193)
			)
			(stroke
				(width 0)
				(type default)
			)
			(fill yes)
			(layer "F.SilkS")
		)
		(fp_line
			(start -0.849884 -1.549908)
			(end 0.849884 -1.549908)
			(stroke
				(width 0.1)
				(type default)
			)
			(layer "F.Fab")
		)
		(fp_line
			(start -0.849884 1.549908)
			(end -0.849884 -1.549908)
			(stroke
				(width 0.1)
				(type default)
			)
			(layer "F.Fab")
		)
		(fp_line
			(start 0.849884 -1.549908)
			(end 0.849884 1.549908)
			(stroke
				(width 0.1)
				(type default)
			)
			(layer "F.Fab")
		)
		(fp_line
			(start 0.849884 1.549908)
			(end -0.849884 1.549908)
			(stroke
				(width 0.1)
				(type default)
			)
			(layer "F.Fab")
		)
		(fp_poly
			(pts
				(xy -3.2004 -1.45796) (xy -3.2004 -0.44196) (xy -2.1844 -0.94996)
			)
			(stroke
				(width 0)
				(type default)
			)
			(fill yes)
			(layer "F.Fab")
		)
		(pad "1" smd rect
			(at -1.35001 -0.94996 270)
			(size 0.6096 1.0668)
			(layers "F.Cu" "F.Mask" "F.Paste")
			(net "UV_ADR_P2V5_COMP")
		)
		(pad "2" smd rect
			(at -1.35001 0 270)
			(size 0.6096 1.0668)
			(layers "F.Cu" "F.Mask" "F.Paste")
			(net "GND")
		)
		(pad "3" smd rect
			(at -1.35001 0.94996 270)
			(size 0.6096 1.0668)
			(layers "F.Cu" "F.Mask" "F.Paste")
			(net "P12V_AUX_UV_ADR_TRIGGER")
		)
		(pad "4" smd rect
			(at 1.35001 0.94996 270)
			(size 0.6096 1.0668)
			(layers "F.Cu" "F.Mask" "F.Paste")
			(net "FM_UV_ADR_TRIGGER_N_R2")
		)
		(pad "5" smd rect
			(at 1.35001 -0.94996 270)
			(size 0.6096 1.0668)
			(layers "F.Cu" "F.Mask" "F.Paste")
			(net "P12V_AUX")
		)
	)
)
